# S9S_MB_2U (Grand Teton) — schematic netlist excerpt (pin names and nets, part order shuffled) for the footprints in the layout excerpt that follows; sources: Cadence DE-HDL packaged netlist, KiCad conversion of 03242023_DA0F0TMBIJ0_F0T_Motherboard_J_brd_V01_OCP.brd

C42  Q_CAP  10UF 16V 10% X6S  pkg C0805  page 95 : A = P12V_S3_AUX_CPU0_NVDIMM ; B = GND
C379  Q_CAP  47UF 4V 20% X6S  pkg C0805  page 75 : A = PVCCIN_CPU0 ; B = GND
R686  Q_RES  499 1% CHIP  pkg 0402LF  page 229 : A = PVNN_TERM_CPU0 ; B = I3C_SPD_DDREFGH_CPU0_SDA

(kicad_pcb
	(version 20260206)
	(generator "pcbnew")
	(generator_version "10.0")
	(general
		(thickness 1.6)
		(legacy_teardrops no)
	)
	(paper "A4")
	(title_block
		(title "03242023_DA0F0TMBIJ0_F0T_Motherboard_J_brd_V01_OCP.brd")
		(comment 1 "Grand Teton / footprints 4990-4992 of 6105")
	)
	(layers
		(0 "F.Cu" signal "TOP")
		(4 "In1.Cu" signal "GND")
		(6 "In2.Cu" signal "IN1")
		(8 "In3.Cu" signal "GND1")
		(10 "In4.Cu" signal "IN2")
		(12 "In5.Cu" signal "GND2")
		(14 "In6.Cu" signal "IN3")
		(16 "In7.Cu" signal "GND3")
		(18 "In8.Cu" signal "VCC")
		(20 "In9.Cu" signal "VCC1")
		(22 "In10.Cu" signal "GND4")
		(24 "In11.Cu" signal "IN4")
		(26 "In12.Cu" signal "GND5")
		(28 "In13.Cu" signal "IN5")
		(30 "In14.Cu" signal "GND6")
		(32 "In15.Cu" signal "IN6")
		(34 "In16.Cu" signal "GND7")
		(2 "B.Cu" signal "BOTTOM")
		(9 "F.Adhes" user "F.Adhesive")
		(11 "B.Adhes" user "B.Adhesive")
		(13 "F.Paste" user "Package Geometry/Pastemask Top")
		(15 "B.Paste" user "Package Geometry/Pastemask Bottom")
		(5 "F.SilkS" user "Ref Des/Silkscreen Top")
		(7 "B.SilkS" user "Ref Des/Silkscreen Bottom")
		(1 "F.Mask" user "Board Geometry/Soldermask Top")
		(3 "B.Mask" user "Board Geometry/Soldermask Bottom")
		(17 "Dwgs.User" user "User.Drawings")
		(19 "Cmts.User" user "User.Comments")
		(21 "Eco1.User" user "User.Eco1")
		(23 "Eco2.User" user "User.Eco2")
		(25 "Edge.Cuts" user "Board Geometry/Outline")
		(27 "Margin" user)
		(31 "F.CrtYd" user "Package Geometry/Place Bound Top")
		(29 "B.CrtYd" user "Package Geometry/Place Bound Bottom")
		(35 "F.Fab" user "Ref Des/Assembly Top")
		(33 "B.Fab" user "Ref Des/Assembly Bottom")
	)
	(footprint ""
		(layer "B.Cu")
		(at 378.711968 -190.795656 -90)
		(property "Reference" "R686"
			(at 0 0 90)
			(layer "B.SilkS")
			(hide yes)
			(effects
				(font
					(size 1.27 1.27)
				)
				(justify mirror)
			)
		)
		(property "Value" ""
			(at 0 0 90)
			(layer "B.Fab")
			(effects
				(font
					(size 1.27 1.27)
				)
				(justify mirror)
			)
		)
		(duplicate_pad_numbers_are_jumpers no)
		(fp_line
			(start -0.7874 0.4064)
			(end 0.7874 0.4064)
			(stroke
				(width 0.1524)
				(type default)
			)
			(layer "B.SilkS")
		)
		(fp_line
			(start 0.7874 0.4064)
			(end 0.7874 -0.4064)
			(stroke
				(width 0.1524)
				(type default)
			)
			(layer "B.SilkS")
		)
		(fp_line
			(start -0.7874 -0.4064)
			(end -0.7874 0.4064)
			(stroke
				(width 0.1524)
				(type default)
			)
			(layer "B.SilkS")
		)
		(fp_line
			(start 0.7874 -0.4064)
			(end -0.7874 -0.4064)
			(stroke
				(width 0.1524)
				(type default)
			)
			(layer "B.SilkS")
		)
		(fp_line
			(start -0.67945 0.3048)
			(end -0.120396 0.3048)
			(stroke
				(width 0.1)
				(type default)
			)
			(layer "B.Fab")
		)
		(fp_line
			(start -0.120396 0.3048)
			(end -0.120396 0.2794)
			(stroke
				(width 0.1)
				(type default)
			)
			(layer "B.Fab")
		)
		(fp_line
			(start 0.12065 0.3048)
			(end 0.67945 0.3048)
			(stroke
				(width 0.1)
				(type default)
			)
			(layer "B.Fab")
		)
		(fp_line
			(start 0.67945 0.3048)
			(end 0.67945 -0.305054)
			(stroke
				(width 0.1)
				(type default)
			)
			(layer "B.Fab")
		)
		(fp_line
			(start -0.120396 0.2794)
			(end 0.12065 0.2794)
			(stroke
				(width 0.1)
				(type default)
			)
			(layer "B.Fab")
		)
		(fp_line
			(start 0.12065 0.2794)
			(end 0.12065 0.3048)
			(stroke
				(width 0.1)
				(type default)
			)
			(layer "B.Fab")
		)
		(fp_line
			(start -0.12065 -0.2794)
			(end -0.12065 -0.3048)
			(stroke
				(width 0.1)
				(type default)
			)
			(layer "B.Fab")
		)
		(fp_line
			(start 0.12065 -0.2794)
			(end -0.12065 -0.2794)
			(stroke
				(width 0.1)
				(type default)
			)
			(layer "B.Fab")
		)
		(fp_line
			(start -0.67945 -0.3048)
			(end -0.67945 0.3048)
			(stroke
				(width 0.1)
				(type default)
			)
			(layer "B.Fab")
		)
		(fp_line
			(start -0.12065 -0.3048)
			(end -0.67945 -0.3048)
			(stroke
				(width 0.1)
				(type default)
			)
			(layer "B.Fab")
		)
		(fp_line
			(start 0.12065 -0.305054)
			(end 0.12065 -0.2794)
			(stroke
				(width 0.1)
				(type default)
			)
			(layer "B.Fab")
		)
		(fp_line
			(start 0.67945 -0.305054)
			(end 0.12065 -0.305054)
			(stroke
				(width 0.1)
				(type default)
			)
			(layer "B.Fab")
		)
		(pad "1" smd circle
			(at 0.40005 0 90)
			(size 0 0)
			(layers "B.Cu" "B.Mask" "B.Paste")
			(net "PVNN_TERM_CPU0")
		)
		(pad "2" smd circle
			(at -0.40005 0 90)
			(size 0 0)
			(layers "B.Cu" "B.Mask" "B.Paste")
			(net "I3C_SPD_DDREFGH_CPU0_SDA")
		)
	)
	(footprint ""
		(layer "B.Cu")
		(at 364.342934 -244.820186 -90)
		(property "Reference" "C379"
			(at 0 0 90)
			(layer "B.SilkS")
			(hide yes)
			(effects
				(font
					(size 1.27 1.27)
				)
				(justify mirror)
			)
		)
		(property "Value" ""
			(at 0 0 90)
			(layer "B.Fab")
			(effects
				(font
					(size 1.27 1.27)
				)
				(justify mirror)
			)
		)
		(duplicate_pad_numbers_are_jumpers no)
		(fp_line
			(start -1.524 0.762)
			(end 1.524 0.762)
			(stroke
				(width 0.1524)
				(type default)
			)
			(layer "B.SilkS")
		)
		(fp_line
			(start 1.524 0.762)
			(end 1.524 -0.762)
			(stroke
				(width 0.1524)
				(type default)
			)
			(layer "B.SilkS")
		)
		(fp_line
			(start -1.524 -0.762)
			(end -1.524 0.762)
			(stroke
				(width 0.1524)
				(type default)
			)
			(layer "B.SilkS")
		)
		(fp_line
			(start 1.524 -0.762)
			(end -1.524 -0.762)
			(stroke
				(width 0.1524)
				(type default)
			)
			(layer "B.SilkS")
		)
		(fp_line
			(start -1.1049 0.724916)
			(end -1.1049 -0.724916)
			(stroke
				(width 0.1)
				(type default)
			)
			(layer "B.Fab")
		)
		(fp_line
			(start 1.1049 0.724916)
			(end -1.1049 0.724916)
			(stroke
				(width 0.1)
				(type default)
			)
			(layer "B.Fab")
		)
		(fp_line
			(start -1.1049 -0.724916)
			(end 1.1049 -0.724916)
			(stroke
				(width 0.1)
				(type default)
			)
			(layer "B.Fab")
		)
		(fp_line
			(start 1.1049 -0.724916)
			(end 1.1049 0.724916)
			(stroke
				(width 0.1)
				(type default)
			)
			(layer "B.Fab")
		)
		(pad "1" smd rect
			(at 0.889 0 270)
			(size 1.016 1.27)
			(layers "B.Cu" "B.Mask" "B.Paste")
			(net "PVCCIN_CPU0")
		)
		(pad "2" smd rect
			(at -0.889 0 270)
			(size 1.016 1.27)
			(layers "B.Cu" "B.Mask" "B.Paste")
			(net "GND")
		)
	)
	(footprint ""
		(layer "B.Cu")
		(at 436.941214 -321.549776 -90)
		(property "Reference" "C42"
			(at 0 0 90)
			(layer "B.SilkS")
			(hide yes)
			(effects
				(font
					(size 1.27 1.27)
				)
				(justify mirror)
			)
		)
		(property "Value" ""
			(at 0 0 90)
			(layer "B.Fab")
			(effects
				(font
					(size 1.27 1.27)
				)
				(justify mirror)
			)
		)
		(duplicate_pad_numbers_are_jumpers no)
		(fp_line
			(start -1.524 0.762)
			(end 1.524 0.762)
			(stroke
				(width 0.1524)
				(type default)
			)
			(layer "B.SilkS")
		)
		(fp_line
			(start 1.524 0.762)
			(end 1.524 -0.762)
			(stroke
				(width 0.1524)
				(type default)
			)
			(layer "B.SilkS")
		)
		(fp_line
			(start -1.524 -0.762)
			(end -1.524 0.762)
			(stroke
				(width 0.1524)
				(type default)
			)
			(layer "B.SilkS")
		)
		(fp_line
			(start 1.524 -0.762)
			(end -1.524 -0.762)
			(stroke
				(width 0.1524)
				(type default)
			)
			(layer "B.SilkS")
		)
		(fp_line
			(start -1.1049 0.724916)
			(end -1.1049 -0.724916)
			(stroke
				(width 0.1)
				(type default)
			)
			(layer "B.Fab")
		)
		(fp_line
			(start 1.1049 0.724916)
			(end -1.1049 0.724916)
			(stroke
				(width 0.1)
				(type default)
			)
			(layer "B.Fab")
		)
		(fp_line
			(start -1.1049 -0.724916)
			(end 1.1049 -0.724916)
			(stroke
				(width 0.1)
				(type default)
			)
			(layer "B.Fab")
		)
		(fp_line
			(start 1.1049 -0.724916)
			(end 1.1049 0.724916)
			(stroke
				(width 0.1)
				(type default)
			)
			(layer "B.Fab")
		)
		(pad "1" smd rect
			(at 0.889 0 270)
			(size 1.016 1.27)
			(layers "B.Cu" "B.Mask" "B.Paste")
			(net "P12V_S3_AUX_CPU0_NVDIMM")
		)
		(pad "2" smd rect
			(at -0.889 0 270)
			(size 1.016 1.27)
			(layers "B.Cu" "B.Mask" "B.Paste")
			(net "GND")
		)
	)
)
